# S9S_MB_2U (Grand Teton) — schematic netlist excerpt (pin names and nets, part order shuffled) for the footprints in the layout excerpt that follows; sources: Cadence DE-HDL packaged netlist, KiCad conversion of 03242023_DA0F0TMBIJ0_F0T_Motherboard_J_brd_V01_OCP.brd

PC1847  Q_CAP  0.22UF 25V 10% X7R  pkg C0402  page 258 : A = SW_P5V_AUX_BST ; B = SW_P5V_AUX_SW
PR633  Q_RES  0 5% EMPTY  pkg 0402LF  page 271 : A = P3V3 ; B = PVCCFA_EHV_FIVRA_CPU0_PVCC2

(kicad_pcb
	(version 20260206)
	(generator "pcbnew")
	(generator_version "10.0")
	(general
		(thickness 1.6)
		(legacy_teardrops no)
	)
	(paper "A4")
	(title_block
		(title "03242023_DA0F0TMBIJ0_F0T_Motherboard_J_brd_V01_OCP.brd")
		(comment 1 "Grand Teton / footprints 224-225 of 6105")
	)
	(layers
		(0 "F.Cu" signal "TOP")
		(4 "In1.Cu" signal "GND")
		(6 "In2.Cu" signal "IN1")
		(8 "In3.Cu" signal "GND1")
		(10 "In4.Cu" signal "IN2")
		(12 "In5.Cu" signal "GND2")
		(14 "In6.Cu" signal "IN3")
		(16 "In7.Cu" signal "GND3")
		(18 "In8.Cu" signal "VCC")
		(20 "In9.Cu" signal "VCC1")
		(22 "In10.Cu" signal "GND4")
		(24 "In11.Cu" signal "IN4")
		(26 "In12.Cu" signal "GND5")
		(28 "In13.Cu" signal "IN5")
		(30 "In14.Cu" signal "GND6")
		(32 "In15.Cu" signal "IN6")
		(34 "In16.Cu" signal "GND7")
		(2 "B.Cu" signal "BOTTOM")
		(9 "F.Adhes" user "F.Adhesive")
		(11 "B.Adhes" user "B.Adhesive")
		(13 "F.Paste" user "Package Geometry/Pastemask Top")
		(15 "B.Paste" user "Package Geometry/Pastemask Bottom")
		(5 "F.SilkS" user "Ref Des/Silkscreen Top")
		(7 "B.SilkS" user "Ref Des/Silkscreen Bottom")
		(1 "F.Mask" user "Board Geometry/Soldermask Top")
		(3 "B.Mask" user "Board Geometry/Soldermask Bottom")
		(17 "Dwgs.User" user "User.Drawings")
		(19 "Cmts.User" user "User.Comments")
		(21 "Eco1.User" user "User.Eco1")
		(23 "Eco2.User" user "User.Eco2")
		(25 "Edge.Cuts" user "Board Geometry/Outline")
		(27 "Margin" user)
		(31 "F.CrtYd" user "Package Geometry/Place Bound Top")
		(29 "B.CrtYd" user "Package Geometry/Place Bound Bottom")
		(35 "F.Fab" user "Ref Des/Assembly Top")
		(33 "B.Fab" user "Ref Des/Assembly Bottom")
	)
	(footprint ""
		(layer "F.Cu")
		(at 283.826712 -362.984796)
		(property "Reference" "PR633"
			(at 0 0 0)
			(layer "F.SilkS")
			(hide yes)
			(effects
				(font
					(size 1.27 1.27)
				)
			)
		)
		(property "Value" ""
			(at 0 0 0)
			(layer "F.Fab")
			(effects
				(font
					(size 1.27 1.27)
				)
			)
		)
		(duplicate_pad_numbers_are_jumpers no)
		(fp_line
			(start -0.7874 -0.4064)
			(end 0.7874 -0.4064)
			(stroke
				(width 0.1524)
				(type default)
			)
			(layer "F.SilkS")
		)
		(fp_line
			(start -0.7874 0.4064)
			(end -0.7874 -0.4064)
			(stroke
				(width 0.1524)
				(type default)
			)
			(layer "F.SilkS")
		)
		(fp_line
			(start 0.7874 -0.4064)
			(end 0.7874 0.4064)
			(stroke
				(width 0.1524)
				(type default)
			)
			(layer "F.SilkS")
		)
		(fp_line
			(start 0.7874 0.4064)
			(end -0.7874 0.4064)
			(stroke
				(width 0.1524)
				(type default)
			)
			(layer "F.SilkS")
		)
		(fp_line
			(start -0.67945 -0.305054)
			(end -0.12065 -0.305054)
			(stroke
				(width 0.1)
				(type default)
			)
			(layer "F.Fab")
		)
		(fp_line
			(start -0.67945 0.3048)
			(end -0.67945 -0.305054)
			(stroke
				(width 0.1)
				(type default)
			)
			(layer "F.Fab")
		)
		(fp_line
			(start -0.12065 -0.305054)
			(end -0.12065 -0.2794)
			(stroke
				(width 0.1)
				(type default)
			)
			(layer "F.Fab")
		)
		(fp_line
			(start -0.12065 -0.2794)
			(end 0.12065 -0.2794)
			(stroke
				(width 0.1)
				(type default)
			)
			(layer "F.Fab")
		)
		(fp_line
			(start -0.12065 0.2794)
			(end -0.12065 0.3048)
			(stroke
				(width 0.1)
				(type default)
			)
			(layer "F.Fab")
		)
		(fp_line
			(start -0.12065 0.3048)
			(end -0.67945 0.3048)
			(stroke
				(width 0.1)
				(type default)
			)
			(layer "F.Fab")
		)
		(fp_line
			(start 0.120396 0.2794)
			(end -0.12065 0.2794)
			(stroke
				(width 0.1)
				(type default)
			)
			(layer "F.Fab")
		)
		(fp_line
			(start 0.120396 0.3048)
			(end 0.120396 0.2794)
			(stroke
				(width 0.1)
				(type default)
			)
			(layer "F.Fab")
		)
		(fp_line
			(start 0.12065 -0.3048)
			(end 0.67945 -0.3048)
			(stroke
				(width 0.1)
				(type default)
			)
			(layer "F.Fab")
		)
		(fp_line
			(start 0.12065 -0.2794)
			(end 0.12065 -0.3048)
			(stroke
				(width 0.1)
				(type default)
			)
			(layer "F.Fab")
		)
		(fp_line
			(start 0.67945 -0.3048)
			(end 0.67945 0.3048)
			(stroke
				(width 0.1)
				(type default)
			)
			(layer "F.Fab")
		)
		(fp_line
			(start 0.67945 0.3048)
			(end 0.120396 0.3048)
			(stroke
				(width 0.1)
				(type default)
			)
			(layer "F.Fab")
		)
		(pad "1" smd circle
			(at -0.40005 0)
			(size 0 0)
			(layers "F.Cu" "F.Mask" "F.Paste")
			(net "P3V3")
		)
		(pad "2" smd circle
			(at 0.40005 0)
			(size 0 0)
			(layers "F.Cu" "F.Mask" "F.Paste")
			(net "PVCCFA_EHV_FIVRA_CPU0_PVCC2")
		)
	)
	(footprint ""
		(layer "F.Cu")
		(at 454.758552 -382.660652 180)
		(property "Reference" "PC1847"
			(at 0 0 180)
			(layer "F.SilkS")
			(hide yes)
			(effects
				(font
					(size 1.27 1.27)
				)
			)
		)
		(property "Value" ""
			(at 0 0 180)
			(layer "F.Fab")
			(effects
				(font
					(size 1.27 1.27)
				)
			)
		)
		(duplicate_pad_numbers_are_jumpers no)
		(fp_line
			(start 0.7874 0.4064)
			(end -0.7874 0.4064)
			(stroke
				(width 0.1524)
				(type default)
			)
			(layer "F.SilkS")
		)
		(fp_line
			(start 0.7874 -0.4064)
			(end 0.7874 0.4064)
			(stroke
				(width 0.1524)
				(type default)
			)
			(layer "F.SilkS")
		)
		(fp_line
			(start -0.7874 0.4064)
			(end -0.7874 -0.4064)
			(stroke
				(width 0.1524)
				(type default)
			)
			(layer "F.SilkS")
		)
		(fp_line
			(start -0.7874 -0.4064)
			(end 0.7874 -0.4064)
			(stroke
				(width 0.1524)
				(type default)
			)
			(layer "F.SilkS")
		)
		(fp_line
			(start 0.67945 0.3048)
			(end 0.120396 0.3048)
			(stroke
				(width 0.1)
				(type default)
			)
			(layer "F.Fab")
		)
		(fp_line
			(start 0.67945 -0.3048)
			(end 0.67945 0.3048)
			(stroke
				(width 0.1)
				(type default)
			)
			(layer "F.Fab")
		)
		(fp_line
			(start 0.12065 -0.2794)
			(end 0.12065 -0.3048)
			(stroke
				(width 0.1)
				(type default)
			)
			(layer "F.Fab")
		)
		(fp_line
			(start 0.12065 -0.3048)
			(end 0.67945 -0.3048)
			(stroke
				(width 0.1)
				(type default)
			)
			(layer "F.Fab")
		)
		(fp_line
			(start 0.120396 0.3048)
			(end 0.120396 0.2794)
			(stroke
				(width 0.1)
				(type default)
			)
			(layer "F.Fab")
		)
		(fp_line
			(start 0.120396 0.2794)
			(end -0.12065 0.2794)
			(stroke
				(width 0.1)
				(type default)
			)
			(layer "F.Fab")
		)
		(fp_line
			(start -0.12065 0.3048)
			(end -0.67945 0.3048)
			(stroke
				(width 0.1)
				(type default)
			)
			(layer "F.Fab")
		)
		(fp_line
			(start -0.12065 0.2794)
			(end -0.12065 0.3048)
			(stroke
				(width 0.1)
				(type default)
			)
			(layer "F.Fab")
		)
		(fp_line
			(start -0.12065 -0.2794)
			(end 0.12065 -0.2794)
			(stroke
				(width 0.1)
				(type default)
			)
			(layer "F.Fab")
		)
		(fp_line
			(start -0.12065 -0.305054)
			(end -0.12065 -0.2794)
			(stroke
				(width 0.1)
				(type default)
			)
			(layer "F.Fab")
		)
		(fp_line
			(start -0.67945 0.3048)
			(end -0.67945 -0.305054)
			(stroke
				(width 0.1)
				(type default)
			)
			(layer "F.Fab")
		)
		(fp_line
			(start -0.67945 -0.305054)
			(end -0.12065 -0.305054)
			(stroke
				(width 0.1)
				(type default)
			)
			(layer "F.Fab")
		)
		(pad "1" smd circle
			(at -0.40005 0 180)
			(size 0 0)
			(layers "F.Cu" "F.Mask" "F.Paste")
			(net "SW_P5V_AUX_BST")
		)
		(pad "2" smd circle
			(at 0.40005 0 180)
			(size 0 0)
			(layers "F.Cu" "F.Mask" "F.Paste")
			(net "SW_P5V_AUX_SW")
		)
	)
)
